# BASEBOARD_FAB2 (Tioga Pass) — schematic netlist excerpt (pin names and nets, part order shuffled) for the footprints in the layout excerpt that follows; sources: Cadence DE-HDL packaged netlist, KiCad conversion of Wiwynn_Tioga_Pass_MB.brd

R8A5  RES  1.00K 1% CHIP  pkg 0402  page 235 : A = P3V3_STBY ; B = IRQ_PVNN_PCH_VRHOT_N
R4D3  RES  27.4 1% CHIP  pkg 0402  page 103 : A = CLK_100M_CPU1_BCLK0_R_DN ; B = CLK_100M_CPU1_BCLK0_DN
R4C11  RES  3.16K 1% CHIP  pkg 0402  page 193 : A = VR_PVCCMCP_CPU1_XADDR2 ; B = GND

(kicad_pcb
	(version 20260206)
	(generator "pcbnew")
	(generator_version "10.0")
	(general
		(thickness 1.6)
		(legacy_teardrops no)
	)
	(paper "A4")
	(title_block
		(title "Wiwynn_Tioga_Pass_MB.brd")
		(comment 1 "Tioga Pass / footprints 222-224 of 4770")
	)
	(layers
		(0 "F.Cu" signal "TOP")
		(4 "In1.Cu" signal "L2GND")
		(6 "In2.Cu" signal "L3")
		(8 "In3.Cu" signal "L4GND")
		(10 "In4.Cu" signal "L5")
		(12 "In5.Cu" signal "L6GND")
		(14 "In6.Cu" signal "L7VCC")
		(16 "In7.Cu" signal "L8VCC")
		(18 "In8.Cu" signal "L9GND")
		(20 "In9.Cu" signal "L10")
		(22 "In10.Cu" signal "L11GND")
		(24 "In11.Cu" signal "L12")
		(26 "In12.Cu" signal "L13GND")
		(2 "B.Cu" signal "BOTTOM")
		(9 "F.Adhes" user "F.Adhesive")
		(11 "B.Adhes" user "B.Adhesive")
		(13 "F.Paste" user "Package Geometry/Pastemask Top")
		(15 "B.Paste" user "Package Geometry/Pastemask Bottom")
		(5 "F.SilkS" user "Ref Des/Silkscreen Top")
		(7 "B.SilkS" user "Ref Des/Silkscreen Bottom")
		(1 "F.Mask" user "Board Geometry/Soldermask Top")
		(3 "B.Mask" user "Board Geometry/Soldermask Bottom")
		(17 "Dwgs.User" user "User.Drawings")
		(19 "Cmts.User" user "User.Comments")
		(21 "Eco1.User" user "User.Eco1")
		(23 "Eco2.User" user "User.Eco2")
		(25 "Edge.Cuts" user "Board Geometry/Outline")
		(27 "Margin" user)
		(31 "F.CrtYd" user "Package Geometry/Place Bound Top")
		(29 "B.CrtYd" user "Package Geometry/Place Bound Bottom")
		(35 "F.Fab" user "Ref Des/Assembly Top")
		(33 "B.Fab" user "Ref Des/Assembly Bottom")
	)
	(footprint ""
		(layer "F.Cu")
		(at 401.13966 -151.72436 -90)
		(property "Reference" "R8A5"
			(at 0 0 270)
			(layer "F.SilkS")
			(hide yes)
			(effects
				(font
					(size 1.27 1.27)
				)
			)
		)
		(property "Value" ""
			(at 0 0 270)
			(layer "F.Fab")
			(effects
				(font
					(size 1.27 1.27)
				)
			)
		)
		(duplicate_pad_numbers_are_jumpers no)
		(fp_poly
			(pts
				(xy -0.2794 -0.1016) (xy 0.2794 -0.1016) (xy 0.2794 0.9906) (xy -0.2794 0.9906)
			)
			(stroke
				(width 0)
				(type default)
			)
			(fill no)
			(layer "F.CrtYd")
		)
		(fp_line
			(start -0.2794 0.9906)
			(end 0.2794 0.9906)
			(stroke
				(width 0.1)
				(type default)
			)
			(layer "F.Fab")
		)
		(fp_line
			(start 0.2794 0.9906)
			(end 0.2794 -0.1016)
			(stroke
				(width 0.1)
				(type default)
			)
			(layer "F.Fab")
		)
		(fp_line
			(start -0.2794 -0.1016)
			(end -0.2794 0.9906)
			(stroke
				(width 0.1)
				(type default)
			)
			(layer "F.Fab")
		)
		(fp_line
			(start 0.2794 -0.1016)
			(end -0.2794 -0.1016)
			(stroke
				(width 0.1)
				(type default)
			)
			(layer "F.Fab")
		)
		(pad "1" smd rect
			(at 0 0 270)
			(size 0.508 0.508)
			(layers "F.Cu" "F.Mask" "F.Paste")
			(net "P3V3_STBY")
		)
		(pad "2" smd rect
			(at 0 0.889 270)
			(size 0.508 0.508)
			(layers "F.Cu" "F.Mask" "F.Paste")
			(net "IRQ_PVNN_PCH_VRHOT_N")
		)
		(zone
			(layer "F.Cu")
			(hatch none 0.5)
			(connect_pads
				(clearance 0)
			)
			(min_thickness 0.25)
			(keepout
				(tracks not_allowed)
				(vias allowed)
				(pads allowed)
				(copperpour not_allowed)
				(footprints allowed)
			)
			(placement
				(enabled no)
				(sheetname "")
			)
			(fill
				(thermal_gap 0.5)
				(thermal_bridge_width 0.5)
				(island_removal_mode 0)
			)
			(polygon
				(pts
					(xy 400.50466 -151.97836) (xy 400.50466 -151.47036) (xy 400.88566 -151.47036) (xy 400.88566 -151.97836)
				)
			)
		)
		(zone
			(layer "F.Cu")
			(hatch none 0.5)
			(connect_pads
				(clearance 0)
			)
			(min_thickness 0.25)
			(keepout
				(tracks allowed)
				(vias not_allowed)
				(pads allowed)
				(copperpour not_allowed)
				(footprints allowed)
			)
			(placement
				(enabled no)
				(sheetname "")
			)
			(fill
				(thermal_gap 0.5)
				(thermal_bridge_width 0.5)
				(island_removal_mode 0)
			)
			(polygon
				(pts
					(xy 400.88566 -151.97836) (xy 400.88566 -151.47036) (xy 400.50466 -151.47036) (xy 400.50466 -151.97836)
				)
			)
		)
	)
	(footprint ""
		(layer "F.Cu")
		(at 176.0728 -106.74985)
		(property "Reference" "R4C11"
			(at 0 0 0)
			(layer "F.SilkS")
			(hide yes)
			(effects
				(font
					(size 1.27 1.27)
				)
			)
		)
		(property "Value" ""
			(at 0 0 0)
			(layer "F.Fab")
			(effects
				(font
					(size 1.27 1.27)
				)
			)
		)
		(duplicate_pad_numbers_are_jumpers no)
		(fp_poly
			(pts
				(xy -0.2794 -0.1016) (xy 0.2794 -0.1016) (xy 0.2794 0.9906) (xy -0.2794 0.9906)
			)
			(stroke
				(width 0)
				(type default)
			)
			(fill no)
			(layer "F.CrtYd")
		)
		(fp_line
			(start -0.2794 -0.1016)
			(end -0.2794 0.9906)
			(stroke
				(width 0.1)
				(type default)
			)
			(layer "F.Fab")
		)
		(fp_line
			(start -0.2794 0.9906)
			(end 0.2794 0.9906)
			(stroke
				(width 0.1)
				(type default)
			)
			(layer "F.Fab")
		)
		(fp_line
			(start 0.2794 -0.1016)
			(end -0.2794 -0.1016)
			(stroke
				(width 0.1)
				(type default)
			)
			(layer "F.Fab")
		)
		(fp_line
			(start 0.2794 0.9906)
			(end 0.2794 -0.1016)
			(stroke
				(width 0.1)
				(type default)
			)
			(layer "F.Fab")
		)
		(pad "1" smd rect
			(at 0 0)
			(size 0.508 0.508)
			(layers "F.Cu" "F.Mask" "F.Paste")
			(net "VR_PVCCMCP_CPU1_XADDR2")
		)
		(pad "2" smd rect
			(at 0 0.889)
			(size 0.508 0.508)
			(layers "F.Cu" "F.Mask" "F.Paste")
			(net "GND")
		)
		(zone
			(layer "F.Cu")
			(hatch none 0.5)
			(connect_pads
				(clearance 0)
			)
			(min_thickness 0.25)
			(keepout
				(tracks allowed)
				(vias not_allowed)
				(pads allowed)
				(copperpour not_allowed)
				(footprints allowed)
			)
			(placement
				(enabled no)
				(sheetname "")
			)
			(fill
				(thermal_gap 0.5)
				(thermal_bridge_width 0.5)
				(island_removal_mode 0)
			)
			(polygon
				(pts
					(xy 175.8188 -106.49585) (xy 176.3268 -106.49585) (xy 176.3268 -106.11485) (xy 175.8188 -106.11485)
				)
			)
		)
		(zone
			(layer "F.Cu")
			(hatch none 0.5)
			(connect_pads
				(clearance 0)
			)
			(min_thickness 0.25)
			(keepout
				(tracks not_allowed)
				(vias allowed)
				(pads allowed)
				(copperpour not_allowed)
				(footprints allowed)
			)
			(placement
				(enabled no)
				(sheetname "")
			)
			(fill
				(thermal_gap 0.5)
				(thermal_bridge_width 0.5)
				(island_removal_mode 0)
			)
			(polygon
				(pts
					(xy 175.8188 -106.11485) (xy 176.3268 -106.11485) (xy 176.3268 -106.49585) (xy 175.8188 -106.49585)
				)
			)
		)
	)
	(footprint ""
		(layer "F.Cu")
		(at 167.386 -86.868 180)
		(property "Reference" "R4D3"
			(at 0 0 180)
			(layer "F.SilkS")
			(hide yes)
			(effects
				(font
					(size 1.27 1.27)
				)
			)
		)
		(property "Value" ""
			(at 0 0 180)
			(layer "F.Fab")
			(effects
				(font
					(size 1.27 1.27)
				)
			)
		)
		(duplicate_pad_numbers_are_jumpers no)
		(fp_poly
			(pts
				(xy -0.2794 -0.1016) (xy 0.2794 -0.1016) (xy 0.2794 0.9906) (xy -0.2794 0.9906)
			)
			(stroke
				(width 0)
				(type default)
			)
			(fill no)
			(layer "F.CrtYd")
		)
		(fp_line
			(start 0.2794 0.9906)
			(end 0.2794 -0.1016)
			(stroke
				(width 0.1)
				(type default)
			)
			(layer "F.Fab")
		)
		(fp_line
			(start 0.2794 -0.1016)
			(end -0.2794 -0.1016)
			(stroke
				(width 0.1)
				(type default)
			)
			(layer "F.Fab")
		)
		(fp_line
			(start -0.2794 0.9906)
			(end 0.2794 0.9906)
			(stroke
				(width 0.1)
				(type default)
			)
			(layer "F.Fab")
		)
		(fp_line
			(start -0.2794 -0.1016)
			(end -0.2794 0.9906)
			(stroke
				(width 0.1)
				(type default)
			)
			(layer "F.Fab")
		)
		(pad "1" smd rect
			(at 0 0 180)
			(size 0.508 0.508)
			(layers "F.Cu" "F.Mask" "F.Paste")
			(net "CLK_100M_CPU1_BCLK0_R_DN")
		)
		(pad "2" smd rect
			(at 0 0.889 180)
			(size 0.508 0.508)
			(layers "F.Cu" "F.Mask" "F.Paste")
			(net "CLK_100M_CPU1_BCLK0_DN")
		)
		(zone
			(layer "F.Cu")
			(hatch none 0.5)
			(connect_pads
				(clearance 0)
			)
			(min_thickness 0.25)
			(keepout
				(tracks not_allowed)
				(vias allowed)
				(pads allowed)
				(copperpour not_allowed)
				(footprints allowed)
			)
			(placement
				(enabled no)
				(sheetname "")
			)
			(fill
				(thermal_gap 0.5)
				(thermal_bridge_width 0.5)
				(island_removal_mode 0)
			)
			(polygon
				(pts
					(xy 167.64 -87.503) (xy 167.132 -87.503) (xy 167.132 -87.122) (xy 167.64 -87.122)
				)
			)
		)
		(zone
			(layer "F.Cu")
			(hatch none 0.5)
			(connect_pads
				(clearance 0)
			)
			(min_thickness 0.25)
			(keepout
				(tracks allowed)
				(vias not_allowed)
				(pads allowed)
				(copperpour not_allowed)
				(footprints allowed)
			)
			(placement
				(enabled no)
				(sheetname "")
			)
			(fill
				(thermal_gap 0.5)
				(thermal_bridge_width 0.5)
				(island_removal_mode 0)
			)
			(polygon
				(pts
					(xy 167.64 -87.122) (xy 167.132 -87.122) (xy 167.132 -87.503) (xy 167.64 -87.503)
				)
			)
		)
	)
)
